(kicad_pcb
	(version 20260206)
	(generator "pcbnew")
	(generator_version "10.0")
	(general
		(thickness 1.6)
		(legacy_teardrops no)
	)
	(paper "A4")
	(title_block
		(title "12092022_DA0F0TFB6D0_F0T_FAN_BOARD_MP5048_D_brd_v02_OCP.brd")
		(comment 1 "Grand Teton / footprints 410-415 of 924")
	)
	(layers
		(0 "F.Cu" signal "TOP")
		(4 "In1.Cu" signal "GND")
		(6 "In2.Cu" signal "IN1")
		(8 "In3.Cu" signal "IN2")
		(10 "In4.Cu" signal "GND1")
		(2 "B.Cu" signal "BOTTOM")
		(9 "F.Adhes" user "F.Adhesive")
		(11 "B.Adhes" user "B.Adhesive")
		(13 "F.Paste" user "Package Geometry/Pastemask Top")
		(15 "B.Paste" user "Package Geometry/Pastemask Bottom")
		(5 "F.SilkS" user "Ref Des/Silkscreen Top")
		(7 "B.SilkS" user "Ref Des/Silkscreen Bottom")
		(1 "F.Mask" user "Board Geometry/Soldermask Top")
		(3 "B.Mask" user "Board Geometry/Soldermask Bottom")
		(17 "Dwgs.User" user "User.Drawings")
		(19 "Cmts.User" user "User.Comments")
		(21 "Eco1.User" user "User.Eco1")
		(23 "Eco2.User" user "User.Eco2")
		(25 "Edge.Cuts" user "Board Geometry/Outline")
		(27 "Margin" user)
		(31 "F.CrtYd" user "Package Geometry/Place Bound Top")
		(29 "B.CrtYd" user "Package Geometry/Place Bound Bottom")
		(35 "F.Fab" user "Ref Des/Assembly Top")
		(33 "B.Fab" user "Ref Des/Assembly Bottom")
	)
	(footprint ""
		(layer "F.Cu")
		(at 3.81 -182.626)
		(property "Reference" "R2356"
			(at 0 0 0)
			(layer "F.SilkS")
			(hide yes)
			(effects
				(font
					(size 1.27 1.27)
				)
			)
		)
		(property "Value" ""
			(at 0 0 0)
			(layer "F.Fab")
			(effects
				(font
					(size 1.27 1.27)
				)
			)
		)
		(duplicate_pad_numbers_are_jumpers no)
		(fp_line
			(start -0.7874 -0.4064)
			(end 0.7874 -0.4064)
			(stroke
				(width 0.1524)
				(type default)
			)
			(layer "F.SilkS")
		)
		(fp_line
			(start -0.7874 0.4064)
			(end -0.7874 -0.4064)
			(stroke
				(width 0.1524)
				(type default)
			)
			(layer "F.SilkS")
		)
		(fp_line
			(start 0.7874 -0.4064)
			(end 0.7874 0.4064)
			(stroke
				(width 0.1524)
				(type default)
			)
			(layer "F.SilkS")
		)
		(fp_line
			(start 0.7874 0.4064)
			(end -0.7874 0.4064)
			(stroke
				(width 0.1524)
				(type default)
			)
			(layer "F.SilkS")
		)
		(fp_line
			(start -0.67945 -0.305054)
			(end -0.12065 -0.305054)
			(stroke
				(width 0.1)
				(type default)
			)
			(layer "F.Fab")
		)
		(fp_line
			(start -0.67945 0.3048)
			(end -0.67945 -0.305054)
			(stroke
				(width 0.1)
				(type default)
			)
			(layer "F.Fab")
		)
		(fp_line
			(start -0.12065 -0.305054)
			(end -0.12065 -0.2794)
			(stroke
				(width 0.1)
				(type default)
			)
			(layer "F.Fab")
		)
		(fp_line
			(start -0.12065 -0.2794)
			(end 0.12065 -0.2794)
			(stroke
				(width 0.1)
				(type default)
			)
			(layer "F.Fab")
		)
		(fp_line
			(start -0.12065 0.2794)
			(end -0.12065 0.3048)
			(stroke
				(width 0.1)
				(type default)
			)
			(layer "F.Fab")
		)
		(fp_line
			(start -0.12065 0.3048)
			(end -0.67945 0.3048)
			(stroke
				(width 0.1)
				(type default)
			)
			(layer "F.Fab")
		)
		(fp_line
			(start 0.120396 0.2794)
			(end -0.12065 0.2794)
			(stroke
				(width 0.1)
				(type default)
			)
			(layer "F.Fab")
		)
		(fp_line
			(start 0.120396 0.3048)
			(end 0.120396 0.2794)
			(stroke
				(width 0.1)
				(type default)
			)
			(layer "F.Fab")
		)
		(fp_line
			(start 0.12065 -0.3048)
			(end 0.67945 -0.3048)
			(stroke
				(width 0.1)
				(type default)
			)
			(layer "F.Fab")
		)
		(fp_line
			(start 0.12065 -0.2794)
			(end 0.12065 -0.3048)
			(stroke
				(width 0.1)
				(type default)
			)
			(layer "F.Fab")
		)
		(fp_line
			(start 0.67945 -0.3048)
			(end 0.67945 0.3048)
			(stroke
				(width 0.1)
				(type default)
			)
			(layer "F.Fab")
		)
		(fp_line
			(start 0.67945 0.3048)
			(end 0.120396 0.3048)
			(stroke
				(width 0.1)
				(type default)
			)
			(layer "F.Fab")
		)
		(pad "1" smd circle
			(at -0.40005 0)
			(size 0 0)
			(layers "F.Cu" "F.Mask" "F.Paste")
			(net "P3V3_AUX")
		)
		(pad "2" smd circle
			(at 0.40005 0)
			(size 0 0)
			(layers "F.Cu" "F.Mask" "F.Paste")
			(net "PCA9555_MB0_A2")
		)
	)
	(footprint ""
		(layer "F.Cu")
		(at 18.669 -106.737912 180)
		(property "Reference" "D250"
			(at -1.397 1.566418 0)
			(unlocked yes)
			(layer "F.SilkS")
			(effects
				(font
					(size 0.7874 0.5842)
					(thickness 0.1524)
				)
				(justify left)
			)
		)
		(property "Value" ""
			(at 0 0 180)
			(layer "F.Fab")
			(effects
				(font
					(size 1.27 1.27)
				)
			)
		)
		(duplicate_pad_numbers_are_jumpers no)
		(fp_line
			(start 0.94488 0.450088)
			(end 0.94488 -0.450088)
			(stroke
				(width 0.1524)
				(type default)
			)
			(layer "F.SilkS")
		)
		(fp_line
			(start 0.94488 -0.450088)
			(end -0.854964 -0.450088)
			(stroke
				(width 0.1524)
				(type default)
			)
			(layer "F.SilkS")
		)
		(fp_line
			(start 0.870458 -0.2794)
			(end 0.845058 0.4064)
			(stroke
				(width 0.1524)
				(type default)
			)
			(layer "F.SilkS")
		)
		(fp_line
			(start 0.845058 0.4064)
			(end 0.845058 -0.381)
			(stroke
				(width 0.1524)
				(type default)
			)
			(layer "F.SilkS")
		)
		(fp_line
			(start -0.854964 0.450088)
			(end 0.925068 0.450088)
			(stroke
				(width 0.1524)
				(type default)
			)
			(layer "F.SilkS")
		)
		(fp_line
			(start -0.854964 -0.450088)
			(end -0.854964 0.450088)
			(stroke
				(width 0.1524)
				(type default)
			)
			(layer "F.SilkS")
		)
		(fp_line
			(start 0.54991 0.350012)
			(end 0.54991 -0.350012)
			(stroke
				(width 0.1)
				(type default)
			)
			(layer "F.Fab")
		)
		(fp_line
			(start 0.54991 -0.350012)
			(end -0.54991 -0.350012)
			(stroke
				(width 0.1)
				(type default)
			)
			(layer "F.Fab")
		)
		(fp_line
			(start -0.54991 0.350012)
			(end 0.54991 0.350012)
			(stroke
				(width 0.1)
				(type default)
			)
			(layer "F.Fab")
		)
		(fp_line
			(start -0.54991 -0.350012)
			(end -0.54991 0.350012)
			(stroke
				(width 0.1)
				(type default)
			)
			(layer "F.Fab")
		)
		(fp_text user "-"
			(at 1.397 1.053338 0)
			(unlocked yes)
			(layer "F.SilkS")
			(effects
				(font
					(size 1.905 1.4224)
					(thickness 0.1524)
				)
				(justify left)
			)
		)
		(fp_text user "+"
			(at -0.762 0.545338 0)
			(unlocked yes)
			(layer "F.SilkS")
			(effects
				(font
					(size 1.905 1.4224)
					(thickness 0.1524)
				)
				(justify left)
			)
		)
		(fp_text user "-"
			(at 2.48539 0.239014 0)
			(unlocked yes)
			(layer "F.Fab")
			(effects
				(font
					(size 1.905 1.4224)
					(thickness 0.1524)
				)
				(justify left)
			)
		)
		(fp_text user "+"
			(at -0.808228 0.239014 0)
			(unlocked yes)
			(layer "F.Fab")
			(effects
				(font
					(size 1.905 1.4224)
					(thickness 0.1524)
				)
				(justify left)
			)
		)
		(pad "A" smd rect
			(at -0.424942 0 180)
			(size 0.5588 0.6096)
			(layers "F.Cu" "F.Mask" "F.Paste")
			(net "GND")
		)
		(pad "C" smd rect
			(at 0.424942 0)
			(size 0.5588 0.6096)
			(layers "F.Cu" "F.Mask" "F.Paste")
			(net "FAN_5_PWM_IL_R")
		)
	)
	(footprint ""
		(layer "F.Cu")
		(at 14.874494 -72.066912)
		(property "Reference" "R5355"
			(at 0 0 0)
			(layer "F.SilkS")
			(hide yes)
			(effects
				(font
					(size 1.27 1.27)
				)
			)
		)
		(property "Value" ""
			(at 0 0 0)
			(layer "F.Fab")
			(effects
				(font
					(size 1.27 1.27)
				)
			)
		)
		(duplicate_pad_numbers_are_jumpers no)
		(fp_line
			(start -0.7874 -0.4064)
			(end 0.7874 -0.4064)
			(stroke
				(width 0.1524)
				(type default)
			)
			(layer "F.SilkS")
		)
		(fp_line
			(start -0.7874 0.4064)
			(end -0.7874 -0.4064)
			(stroke
				(width 0.1524)
				(type default)
			)
			(layer "F.SilkS")
		)
		(fp_line
			(start 0.7874 -0.4064)
			(end 0.7874 0.4064)
			(stroke
				(width 0.1524)
				(type default)
			)
			(layer "F.SilkS")
		)
		(fp_line
			(start 0.7874 0.4064)
			(end -0.7874 0.4064)
			(stroke
				(width 0.1524)
				(type default)
			)
			(layer "F.SilkS")
		)
		(fp_line
			(start -0.67945 -0.305054)
			(end -0.12065 -0.305054)
			(stroke
				(width 0.1)
				(type default)
			)
			(layer "F.Fab")
		)
		(fp_line
			(start -0.67945 0.3048)
			(end -0.67945 -0.305054)
			(stroke
				(width 0.1)
				(type default)
			)
			(layer "F.Fab")
		)
		(fp_line
			(start -0.12065 -0.305054)
			(end -0.12065 -0.2794)
			(stroke
				(width 0.1)
				(type default)
			)
			(layer "F.Fab")
		)
		(fp_line
			(start -0.12065 -0.2794)
			(end 0.12065 -0.2794)
			(stroke
				(width 0.1)
				(type default)
			)
			(layer "F.Fab")
		)
		(fp_line
			(start -0.12065 0.2794)
			(end -0.12065 0.3048)
			(stroke
				(width 0.1)
				(type default)
			)
			(layer "F.Fab")
		)
		(fp_line
			(start -0.12065 0.3048)
			(end -0.67945 0.3048)
			(stroke
				(width 0.1)
				(type default)
			)
			(layer "F.Fab")
		)
		(fp_line
			(start 0.120396 0.2794)
			(end -0.12065 0.2794)
			(stroke
				(width 0.1)
				(type default)
			)
			(layer "F.Fab")
		)
		(fp_line
			(start 0.120396 0.3048)
			(end 0.120396 0.2794)
			(stroke
				(width 0.1)
				(type default)
			)
			(layer "F.Fab")
		)
		(fp_line
			(start 0.12065 -0.3048)
			(end 0.67945 -0.3048)
			(stroke
				(width 0.1)
				(type default)
			)
			(layer "F.Fab")
		)
		(fp_line
			(start 0.12065 -0.2794)
			(end 0.12065 -0.3048)
			(stroke
				(width 0.1)
				(type default)
			)
			(layer "F.Fab")
		)
		(fp_line
			(start 0.67945 -0.3048)
			(end 0.67945 0.3048)
			(stroke
				(width 0.1)
				(type default)
			)
			(layer "F.Fab")
		)
		(fp_line
			(start 0.67945 0.3048)
			(end 0.120396 0.3048)
			(stroke
				(width 0.1)
				(type default)
			)
			(layer "F.Fab")
		)
		(pad "1" smd circle
			(at -0.40005 0)
			(size 0 0)
			(layers "F.Cu" "F.Mask" "F.Paste")
			(net "FAN_5_PRESENT_R")
		)
		(pad "2" smd circle
			(at 0.40005 0)
			(size 0 0)
			(layers "F.Cu" "F.Mask" "F.Paste")
			(net "FAN_5_PRESENT")
		)
	)
	(footprint ""
		(layer "F.Cu")
		(at 38.6461 -130.048)
		(property "Reference" "R5579"
			(at 0 0 0)
			(layer "F.SilkS")
			(hide yes)
			(effects
				(font
					(size 1.27 1.27)
				)
			)
		)
		(property "Value" ""
			(at 0 0 0)
			(layer "F.Fab")
			(effects
				(font
					(size 1.27 1.27)
				)
			)
		)
		(duplicate_pad_numbers_are_jumpers no)
		(fp_line
			(start -0.7874 -0.4064)
			(end 0.7874 -0.4064)
			(stroke
				(width 0.1524)
				(type default)
			)
			(layer "F.SilkS")
		)
		(fp_line
			(start -0.7874 0.4064)
			(end -0.7874 -0.4064)
			(stroke
				(width 0.1524)
				(type default)
			)
			(layer "F.SilkS")
		)
		(fp_line
			(start 0.7874 -0.4064)
			(end 0.7874 0.4064)
			(stroke
				(width 0.1524)
				(type default)
			)
			(layer "F.SilkS")
		)
		(fp_line
			(start 0.7874 0.4064)
			(end -0.7874 0.4064)
			(stroke
				(width 0.1524)
				(type default)
			)
			(layer "F.SilkS")
		)
		(fp_line
			(start -0.67945 -0.305054)
			(end -0.12065 -0.305054)
			(stroke
				(width 0.1)
				(type default)
			)
			(layer "F.Fab")
		)
		(fp_line
			(start -0.67945 0.3048)
			(end -0.67945 -0.305054)
			(stroke
				(width 0.1)
				(type default)
			)
			(layer "F.Fab")
		)
		(fp_line
			(start -0.12065 -0.305054)
			(end -0.12065 -0.2794)
			(stroke
				(width 0.1)
				(type default)
			)
			(layer "F.Fab")
		)
		(fp_line
			(start -0.12065 -0.2794)
			(end 0.12065 -0.2794)
			(stroke
				(width 0.1)
				(type default)
			)
			(layer "F.Fab")
		)
		(fp_line
			(start -0.12065 0.2794)
			(end -0.12065 0.3048)
			(stroke
				(width 0.1)
				(type default)
			)
			(layer "F.Fab")
		)
		(fp_line
			(start -0.12065 0.3048)
			(end -0.67945 0.3048)
			(stroke
				(width 0.1)
				(type default)
			)
			(layer "F.Fab")
		)
		(fp_line
			(start 0.120396 0.2794)
			(end -0.12065 0.2794)
			(stroke
				(width 0.1)
				(type default)
			)
			(layer "F.Fab")
		)
		(fp_line
			(start 0.120396 0.3048)
			(end 0.120396 0.2794)
			(stroke
				(width 0.1)
				(type default)
			)
			(layer "F.Fab")
		)
		(fp_line
			(start 0.12065 -0.3048)
			(end 0.67945 -0.3048)
			(stroke
				(width 0.1)
				(type default)
			)
			(layer "F.Fab")
		)
		(fp_line
			(start 0.12065 -0.2794)
			(end 0.12065 -0.3048)
			(stroke
				(width 0.1)
				(type default)
			)
			(layer "F.Fab")
		)
		(fp_line
			(start 0.67945 -0.3048)
			(end 0.67945 0.3048)
			(stroke
				(width 0.1)
				(type default)
			)
			(layer "F.Fab")
		)
		(fp_line
			(start 0.67945 0.3048)
			(end 0.120396 0.3048)
			(stroke
				(width 0.1)
				(type default)
			)
			(layer "F.Fab")
		)
		(pad "1" smd rect
			(at -0.40005 0 180)
			(size 0.4572 0.508)
			(layers "F.Cu" "F.Mask" "F.Paste")
			(net "FAN_2_PWM")
		)
		(pad "2" smd rect
			(at 0.40005 0 180)
			(size 0.4572 0.508)
			(layers "F.Cu" "F.Mask" "F.Paste")
			(net "FAN_2_PWM_R2")
		)
	)
	(footprint ""
		(layer "F.Cu")
		(at 21.717 -211.328 90)
		(property "Reference" "C2087"
			(at 0 0 90)
			(layer "F.SilkS")
			(hide yes)
			(effects
				(font
					(size 1.27 1.27)
				)
			)
		)
		(property "Value" ""
			(at 0 0 90)
			(layer "F.Fab")
			(effects
				(font
					(size 1.27 1.27)
				)
			)
		)
		(duplicate_pad_numbers_are_jumpers no)
		(fp_line
			(start 0.7874 -0.4064)
			(end 0.7874 0.4064)
			(stroke
				(width 0.1524)
				(type default)
			)
			(layer "F.SilkS")
		)
		(fp_line
			(start -0.7874 -0.4064)
			(end 0.7874 -0.4064)
			(stroke
				(width 0.1524)
				(type default)
			)
			(layer "F.SilkS")
		)
		(fp_line
			(start 0.7874 0.4064)
			(end -0.7874 0.4064)
			(stroke
				(width 0.1524)
				(type default)
			)
			(layer "F.SilkS")
		)
		(fp_line
			(start -0.7874 0.4064)
			(end -0.7874 -0.4064)
			(stroke
				(width 0.1524)
				(type default)
			)
			(layer "F.SilkS")
		)
		(fp_line
			(start -0.12065 -0.305054)
			(end -0.12065 -0.2794)
			(stroke
				(width 0.1)
				(type default)
			)
			(layer "F.Fab")
		)
		(fp_line
			(start -0.67945 -0.305054)
			(end -0.12065 -0.305054)
			(stroke
				(width 0.1)
				(type default)
			)
			(layer "F.Fab")
		)
		(fp_line
			(start 0.67945 -0.3048)
			(end 0.67945 0.3048)
			(stroke
				(width 0.1)
				(type default)
			)
			(layer "F.Fab")
		)
		(fp_line
			(start 0.12065 -0.3048)
			(end 0.67945 -0.3048)
			(stroke
				(width 0.1)
				(type default)
			)
			(layer "F.Fab")
		)
		(fp_line
			(start 0.12065 -0.2794)
			(end 0.12065 -0.3048)
			(stroke
				(width 0.1)
				(type default)
			)
			(layer "F.Fab")
		)
		(fp_line
			(start -0.12065 -0.2794)
			(end 0.12065 -0.2794)
			(stroke
				(width 0.1)
				(type default)
			)
			(layer "F.Fab")
		)
		(fp_line
			(start 0.120396 0.2794)
			(end -0.12065 0.2794)
			(stroke
				(width 0.1)
				(type default)
			)
			(layer "F.Fab")
		)
		(fp_line
			(start -0.12065 0.2794)
			(end -0.12065 0.3048)
			(stroke
				(width 0.1)
				(type default)
			)
			(layer "F.Fab")
		)
		(fp_line
			(start 0.67945 0.3048)
			(end 0.120396 0.3048)
			(stroke
				(width 0.1)
				(type default)
			)
			(layer "F.Fab")
		)
		(fp_line
			(start 0.120396 0.3048)
			(end 0.120396 0.2794)
			(stroke
				(width 0.1)
				(type default)
			)
			(layer "F.Fab")
		)
		(fp_line
			(start -0.12065 0.3048)
			(end -0.67945 0.3048)
			(stroke
				(width 0.1)
				(type default)
			)
			(layer "F.Fab")
		)
		(fp_line
			(start -0.67945 0.3048)
			(end -0.67945 -0.305054)
			(stroke
				(width 0.1)
				(type default)
			)
			(layer "F.Fab")
		)
		(pad "1" smd circle
			(at -0.40005 0 90)
			(size 0 0)
			(layers "F.Cu" "F.Mask" "F.Paste")
			(net "P3V3_AUX")
		)
		(pad "2" smd circle
			(at 0.40005 0 90)
			(size 0 0)
			(layers "F.Cu" "F.Mask" "F.Paste")
			(net "GND")
		)
	)
	(footprint ""
		(layer "F.Cu")
		(at 33.782 -287.147 -90)
		(property "Reference" "R5303"
			(at 0 0 270)
			(layer "F.SilkS")
			(hide yes)
			(effects
				(font
					(size 1.27 1.27)
				)
			)
		)
		(property "Value" ""
			(at 0 0 270)
			(layer "F.Fab")
			(effects
				(font
					(size 1.27 1.27)
				)
			)
		)
		(duplicate_pad_numbers_are_jumpers no)
		(fp_line
			(start -0.7874 0.4064)
			(end -0.7874 -0.4064)
			(stroke
				(width 0.1524)
				(type default)
			)
			(layer "F.SilkS")
		)
		(fp_line
			(start 0.7874 0.4064)
			(end -0.7874 0.4064)
			(stroke
				(width 0.1524)
				(type default)
			)
			(layer "F.SilkS")
		)
		(fp_line
			(start -0.7874 -0.4064)
			(end 0.7874 -0.4064)
			(stroke
				(width 0.1524)
				(type default)
			)
			(layer "F.SilkS")
		)
		(fp_line
			(start 0.7874 -0.4064)
			(end 0.7874 0.4064)
			(stroke
				(width 0.1524)
				(type default)
			)
			(layer "F.SilkS")
		)
		(fp_line
			(start -0.67945 0.3048)
			(end -0.67945 -0.305054)
			(stroke
				(width 0.1)
				(type default)
			)
			(layer "F.Fab")
		)
		(fp_line
			(start -0.12065 0.3048)
			(end -0.67945 0.3048)
			(stroke
				(width 0.1)
				(type default)
			)
			(layer "F.Fab")
		)
		(fp_line
			(start 0.120396 0.3048)
			(end 0.120396 0.2794)
			(stroke
				(width 0.1)
				(type default)
			)
			(layer "F.Fab")
		)
		(fp_line
			(start 0.67945 0.3048)
			(end 0.120396 0.3048)
			(stroke
				(width 0.1)
				(type default)
			)
			(layer "F.Fab")
		)
		(fp_line
			(start -0.12065 0.2794)
			(end -0.12065 0.3048)
			(stroke
				(width 0.1)
				(type default)
			)
			(layer "F.Fab")
		)
		(fp_line
			(start 0.120396 0.2794)
			(end -0.12065 0.2794)
			(stroke
				(width 0.1)
				(type default)
			)
			(layer "F.Fab")
		)
		(fp_line
			(start -0.12065 -0.2794)
			(end 0.12065 -0.2794)
			(stroke
				(width 0.1)
				(type default)
			)
			(layer "F.Fab")
		)
		(fp_line
			(start 0.12065 -0.2794)
			(end 0.12065 -0.3048)
			(stroke
				(width 0.1)
				(type default)
			)
			(layer "F.Fab")
		)
		(fp_line
			(start 0.12065 -0.3048)
			(end 0.67945 -0.3048)
			(stroke
				(width 0.1)
				(type default)
			)
			(layer "F.Fab")
		)
		(fp_line
			(start 0.67945 -0.3048)
			(end 0.67945 0.3048)
			(stroke
				(width 0.1)
				(type default)
			)
			(layer "F.Fab")
		)
		(fp_line
			(start -0.67945 -0.305054)
			(end -0.12065 -0.305054)
			(stroke
				(width 0.1)
				(type default)
			)
			(layer "F.Fab")
		)
		(fp_line
			(start -0.12065 -0.305054)
			(end -0.12065 -0.2794)
			(stroke
				(width 0.1)
				(type default)
			)
			(layer "F.Fab")
		)
		(pad "1" smd rect
			(at -0.40005 0 90)
			(size 0.4572 0.508)
			(layers "F.Cu" "F.Mask" "F.Paste")
			(net "FAN_0_TACH_OL_R")
		)
		(pad "2" smd rect
			(at 0.40005 0 90)
			(size 0.4572 0.508)
			(layers "F.Cu" "F.Mask" "F.Paste")
			(net "FAN_0_TACH_OL")
		)
	)
)
